# BASEBOARD_FAB2 (Tioga Pass) — schematic netlist excerpt (pin names and nets, part order shuffled) for the footprints in the layout excerpt that follows; sources: Cadence DE-HDL packaged netlist, KiCad conversion of Wiwynn_Tioga_Pass_MB.brd

C7G34  CAP  0.22UF 16V 10% X7R  pkg 0402  page 216 : A = P5V_STBY ; B = GND
R4D12  RES  27.4 1% CHIP  pkg 0402  page 103 : A = CLK_100M_CPU0_PE_REFCLK_R_DP ; B = CLK_100M_CPU0_PE_REFCLK_DP
CR1F1  DIODE  SDMK0340L IC  pkg SM  page 161 : C = FAN_TACH0_CPU0_D1 ; A = FAN_TACH0_CPU0_D2

(kicad_pcb
	(version 20260206)
	(generator "pcbnew")
	(generator_version "10.0")
	(general
		(thickness 1.6)
		(legacy_teardrops no)
	)
	(paper "A4")
	(title_block
		(title "Wiwynn_Tioga_Pass_MB.brd")
		(comment 1 "Tioga Pass / footprints 2048-2050 of 4770")
	)
	(layers
		(0 "F.Cu" signal "TOP")
		(4 "In1.Cu" signal "L2GND")
		(6 "In2.Cu" signal "L3")
		(8 "In3.Cu" signal "L4GND")
		(10 "In4.Cu" signal "L5")
		(12 "In5.Cu" signal "L6GND")
		(14 "In6.Cu" signal "L7VCC")
		(16 "In7.Cu" signal "L8VCC")
		(18 "In8.Cu" signal "L9GND")
		(20 "In9.Cu" signal "L10")
		(22 "In10.Cu" signal "L11GND")
		(24 "In11.Cu" signal "L12")
		(26 "In12.Cu" signal "L13GND")
		(2 "B.Cu" signal "BOTTOM")
		(9 "F.Adhes" user "F.Adhesive")
		(11 "B.Adhes" user "B.Adhesive")
		(13 "F.Paste" user "Package Geometry/Pastemask Top")
		(15 "B.Paste" user "Package Geometry/Pastemask Bottom")
		(5 "F.SilkS" user "Ref Des/Silkscreen Top")
		(7 "B.SilkS" user "Ref Des/Silkscreen Bottom")
		(1 "F.Mask" user "Board Geometry/Soldermask Top")
		(3 "B.Mask" user "Board Geometry/Soldermask Bottom")
		(17 "Dwgs.User" user "User.Drawings")
		(19 "Cmts.User" user "User.Comments")
		(21 "Eco1.User" user "User.Eco1")
		(23 "Eco2.User" user "User.Eco2")
		(25 "Edge.Cuts" user "Board Geometry/Outline")
		(27 "Margin" user)
		(31 "F.CrtYd" user "Package Geometry/Place Bound Top")
		(29 "B.CrtYd" user "Package Geometry/Place Bound Bottom")
		(35 "F.Fab" user "Ref Des/Assembly Top")
		(33 "B.Fab" user "Ref Des/Assembly Bottom")
	)
	(footprint ""
		(layer "F.Cu")
		(at 347.1926 -10.2108 -90)
		(property "Reference" "C7G34"
			(at 0 0 270)
			(layer "F.SilkS")
			(hide yes)
			(effects
				(font
					(size 1.27 1.27)
				)
			)
		)
		(property "Value" ""
			(at 0 0 270)
			(layer "F.Fab")
			(effects
				(font
					(size 1.27 1.27)
				)
			)
		)
		(duplicate_pad_numbers_are_jumpers no)
		(fp_rect
			(start -0.3048 -0.1016)
			(end 0.3048 0.9906)
			(stroke
				(width 0)
				(type default)
			)
			(fill no)
			(layer "F.CrtYd")
		)
		(fp_line
			(start -0.3048 0.9906)
			(end 0.3048 0.9906)
			(stroke
				(width 0.1)
				(type default)
			)
			(layer "F.Fab")
		)
		(fp_line
			(start 0.3048 0.9906)
			(end 0.3048 -0.1016)
			(stroke
				(width 0.1)
				(type default)
			)
			(layer "F.Fab")
		)
		(fp_line
			(start -0.3048 -0.1016)
			(end -0.3048 0.9906)
			(stroke
				(width 0.1)
				(type default)
			)
			(layer "F.Fab")
		)
		(fp_line
			(start 0.3048 -0.1016)
			(end -0.3048 -0.1016)
			(stroke
				(width 0.1)
				(type default)
			)
			(layer "F.Fab")
		)
		(pad "1" smd rect
			(at 0 0 270)
			(size 0.508 0.508)
			(layers "F.Cu" "F.Mask" "F.Paste")
			(net "P5V_STBY")
		)
		(pad "2" smd rect
			(at 0 0.889 270)
			(size 0.508 0.508)
			(layers "F.Cu" "F.Mask" "F.Paste")
			(net "GND")
		)
		(zone
			(layer "F.Cu")
			(hatch none 0.5)
			(connect_pads
				(clearance 0)
			)
			(min_thickness 0.25)
			(keepout
				(tracks not_allowed)
				(vias allowed)
				(pads allowed)
				(copperpour not_allowed)
				(footprints allowed)
			)
			(placement
				(enabled no)
				(sheetname "")
			)
			(fill
				(thermal_gap 0.5)
				(thermal_bridge_width 0.5)
				(island_removal_mode 0)
			)
			(polygon
				(pts
					(xy 346.9386 -10.4648) (xy 346.5576 -10.4648) (xy 346.5576 -9.9568) (xy 346.9386 -9.9568)
				)
			)
		)
		(zone
			(layer "F.Cu")
			(hatch none 0.5)
			(connect_pads
				(clearance 0)
			)
			(min_thickness 0.25)
			(keepout
				(tracks allowed)
				(vias not_allowed)
				(pads allowed)
				(copperpour not_allowed)
				(footprints allowed)
			)
			(placement
				(enabled no)
				(sheetname "")
			)
			(fill
				(thermal_gap 0.5)
				(thermal_bridge_width 0.5)
				(island_removal_mode 0)
			)
			(polygon
				(pts
					(xy 346.9386 -10.4648) (xy 346.5576 -10.4648) (xy 346.5576 -9.9568) (xy 346.9386 -9.9568)
				)
			)
		)
	)
	(footprint ""
		(layer "F.Cu")
		(at 175.387 -83.947 90)
		(property "Reference" "R4D12"
			(at 0 0 90)
			(layer "F.SilkS")
			(hide yes)
			(effects
				(font
					(size 1.27 1.27)
				)
			)
		)
		(property "Value" ""
			(at 0 0 90)
			(layer "F.Fab")
			(effects
				(font
					(size 1.27 1.27)
				)
			)
		)
		(duplicate_pad_numbers_are_jumpers no)
		(fp_poly
			(pts
				(xy -0.2794 -0.1016) (xy 0.2794 -0.1016) (xy 0.2794 0.9906) (xy -0.2794 0.9906)
			)
			(stroke
				(width 0)
				(type default)
			)
			(fill no)
			(layer "F.CrtYd")
		)
		(fp_line
			(start 0.2794 -0.1016)
			(end -0.2794 -0.1016)
			(stroke
				(width 0.1)
				(type default)
			)
			(layer "F.Fab")
		)
		(fp_line
			(start -0.2794 -0.1016)
			(end -0.2794 0.9906)
			(stroke
				(width 0.1)
				(type default)
			)
			(layer "F.Fab")
		)
		(fp_line
			(start 0.2794 0.9906)
			(end 0.2794 -0.1016)
			(stroke
				(width 0.1)
				(type default)
			)
			(layer "F.Fab")
		)
		(fp_line
			(start -0.2794 0.9906)
			(end 0.2794 0.9906)
			(stroke
				(width 0.1)
				(type default)
			)
			(layer "F.Fab")
		)
		(pad "1" smd rect
			(at 0 0 90)
			(size 0.508 0.508)
			(layers "F.Cu" "F.Mask" "F.Paste")
			(net "CLK_100M_CPU0_PE_REFCLK_R_DP")
		)
		(pad "2" smd rect
			(at 0 0.889 90)
			(size 0.508 0.508)
			(layers "F.Cu" "F.Mask" "F.Paste")
			(net "CLK_100M_CPU0_PE_REFCLK_DP")
		)
		(zone
			(layer "F.Cu")
			(hatch none 0.5)
			(connect_pads
				(clearance 0)
			)
			(min_thickness 0.25)
			(keepout
				(tracks allowed)
				(vias not_allowed)
				(pads allowed)
				(copperpour not_allowed)
				(footprints allowed)
			)
			(placement
				(enabled no)
				(sheetname "")
			)
			(fill
				(thermal_gap 0.5)
				(thermal_bridge_width 0.5)
				(island_removal_mode 0)
			)
			(polygon
				(pts
					(xy 175.641 -83.693) (xy 175.641 -84.201) (xy 176.022 -84.201) (xy 176.022 -83.693)
				)
			)
		)
		(zone
			(layer "F.Cu")
			(hatch none 0.5)
			(connect_pads
				(clearance 0)
			)
			(min_thickness 0.25)
			(keepout
				(tracks not_allowed)
				(vias allowed)
				(pads allowed)
				(copperpour not_allowed)
				(footprints allowed)
			)
			(placement
				(enabled no)
				(sheetname "")
			)
			(fill
				(thermal_gap 0.5)
				(thermal_bridge_width 0.5)
				(island_removal_mode 0)
			)
			(polygon
				(pts
					(xy 176.022 -83.693) (xy 176.022 -84.201) (xy 175.641 -84.201) (xy 175.641 -83.693)
				)
			)
		)
	)
	(footprint ""
		(layer "F.Cu")
		(at 24.257 -32.385)
		(property "Reference" "CR1F1"
			(at 1.651 -1.11633 0)
			(unlocked yes)
			(layer "F.SilkS")
			(effects
				(font
					(size 0.7874 0.5842)
					(thickness 0.1524)
				)
				(justify left)
			)
		)
		(property "Value" ""
			(at 0 0 0)
			(layer "F.Fab")
			(effects
				(font
					(size 1.27 1.27)
				)
			)
		)
		(duplicate_pad_numbers_are_jumpers no)
		(fp_line
			(start -1.8161 1.664462)
			(end -1.335278 0.831596)
			(stroke
				(width 0.1524)
				(type default)
			)
			(layer "F.SilkS")
		)
		(fp_line
			(start -1.335278 -0.291846)
			(end -1.335278 0.831596)
			(stroke
				(width 0.1524)
				(type default)
			)
			(layer "F.SilkS")
		)
		(fp_line
			(start -1.335278 0.831596)
			(end -0.854456 1.664462)
			(stroke
				(width 0.1524)
				(type default)
			)
			(layer "F.SilkS")
		)
		(fp_line
			(start -1.335278 1.664462)
			(end -1.8161 1.664462)
			(stroke
				(width 0.1524)
				(type default)
			)
			(layer "F.SilkS")
		)
		(fp_line
			(start -1.335278 2.576068)
			(end -1.335278 1.664462)
			(stroke
				(width 0.1524)
				(type default)
			)
			(layer "F.SilkS")
		)
		(fp_line
			(start -0.854456 0.831596)
			(end -1.8161 0.831596)
			(stroke
				(width 0.1524)
				(type default)
			)
			(layer "F.SilkS")
		)
		(fp_line
			(start -0.854456 1.664462)
			(end -1.335278 1.664462)
			(stroke
				(width 0.1524)
				(type default)
			)
			(layer "F.SilkS")
		)
		(fp_rect
			(start -0.67437 2.04216)
			(end 0.67437 0.24384)
			(stroke
				(width 0)
				(type default)
			)
			(fill no)
			(layer "F.CrtYd")
		)
		(fp_line
			(start -1.8161 1.664462)
			(end -1.335278 0.831596)
			(stroke
				(width 0.1)
				(type default)
			)
			(layer "F.Fab")
		)
		(fp_line
			(start -1.335278 0.831596)
			(end -1.335278 -0.291846)
			(stroke
				(width 0.1)
				(type default)
			)
			(layer "F.Fab")
		)
		(fp_line
			(start -1.335278 0.831596)
			(end -0.854456 1.664462)
			(stroke
				(width 0.1)
				(type default)
			)
			(layer "F.Fab")
		)
		(fp_line
			(start -1.335278 1.664462)
			(end -1.335278 2.576068)
			(stroke
				(width 0.1)
				(type default)
			)
			(layer "F.Fab")
		)
		(fp_line
			(start -0.854456 0.831596)
			(end -1.8161 0.831596)
			(stroke
				(width 0.1)
				(type default)
			)
			(layer "F.Fab")
		)
		(fp_line
			(start -0.854456 1.664462)
			(end -1.8161 1.664462)
			(stroke
				(width 0.1)
				(type default)
			)
			(layer "F.Fab")
		)
		(fp_line
			(start -0.67437 0.24384)
			(end -0.67437 2.04216)
			(stroke
				(width 0.1)
				(type default)
			)
			(layer "F.Fab")
		)
		(fp_line
			(start -0.67437 2.04216)
			(end 0.67437 2.04216)
			(stroke
				(width 0.1)
				(type default)
			)
			(layer "F.Fab")
		)
		(fp_line
			(start 0.67437 0.24384)
			(end -0.67437 0.24384)
			(stroke
				(width 0.1)
				(type default)
			)
			(layer "F.Fab")
		)
		(fp_line
			(start 0.67437 2.04216)
			(end 0.67437 0.24384)
			(stroke
				(width 0.1)
				(type default)
			)
			(layer "F.Fab")
		)
		(pad "1" smd rect
			(at 0 0)
			(size 0.4064 1.016)
			(layers "F.Cu" "F.Mask" "F.Paste")
			(net "FAN_TACH0_CPU0_D1")
		)
		(pad "2" smd rect
			(at 0 2.286)
			(size 0.4064 1.016)
			(layers "F.Cu" "F.Mask" "F.Paste")
			(net "FAN_TACH0_CPU0_D2")
		)
	)
)
